# BASEBOARD_FAB2 (Tioga Pass) — schematic netlist excerpt (pin names and nets, part order shuffled) for the footprints in the layout excerpt that follows; sources: Cadence DE-HDL packaged netlist, KiCad conversion of Wiwynn_Tioga_Pass_MB.brd

JA9G1  SKT-RJ45-LED-XFOR-1-GP  pkg SOCKET-G2  page 141
  \1\  = GND
  \2\  = GND
  L1  = LED_LAN_2_R_N
  L2  = LED_LAN_0_R_N
  L3  = LED_LAN_1_R_N
  L4  = NIC_LED_ACT_ANODE_R
  R1  = GND_LAN_TRCT1234_C
  R2  = NIC_MDI_SPRV_RJ45_0_R_DP
  R3  = NIC_MDI_SPRV_RJ45_0_R_DN
  R4  = NIC_MDI_SPRV_RJ45_1_R_DP
  R5  = NIC_MDI_SPRV_RJ45_1_R_DN
  R6  = GND
  R7  = NIC_MDI_SPRV_RJ45_2_R_DP
  R8  = NIC_MDI_SPRV_RJ45_2_R_DN
  R9  = NIC_MDI_SPRV_RJ45_3_R_DP
  R10  = NIC_MDI_SPRV_RJ45_3_R_DN
  R11  = GND_LAN_TRCT1234_C

(kicad_pcb
	(version 20260206)
	(generator "pcbnew")
	(generator_version "10.0")
	(general
		(thickness 1.6)
		(legacy_teardrops no)
	)
	(paper "A4")
	(title_block
		(title "Wiwynn_Tioga_Pass_MB.brd")
		(comment 1 "Tioga Pass / footprint 343 of 4770 (JA9G1), pads 1-17 of 17")
	)
	(layers
		(0 "F.Cu" signal "TOP")
		(4 "In1.Cu" signal "L2GND")
		(6 "In2.Cu" signal "L3")
		(8 "In3.Cu" signal "L4GND")
		(10 "In4.Cu" signal "L5")
		(12 "In5.Cu" signal "L6GND")
		(14 "In6.Cu" signal "L7VCC")
		(16 "In7.Cu" signal "L8VCC")
		(18 "In8.Cu" signal "L9GND")
		(20 "In9.Cu" signal "L10")
		(22 "In10.Cu" signal "L11GND")
		(24 "In11.Cu" signal "L12")
		(26 "In12.Cu" signal "L13GND")
		(2 "B.Cu" signal "BOTTOM")
		(9 "F.Adhes" user "F.Adhesive")
		(11 "B.Adhes" user "B.Adhesive")
		(13 "F.Paste" user "Package Geometry/Pastemask Top")
		(15 "B.Paste" user "Package Geometry/Pastemask Bottom")
		(5 "F.SilkS" user "Ref Des/Silkscreen Top")
		(7 "B.SilkS" user "Ref Des/Silkscreen Bottom")
		(1 "F.Mask" user "Board Geometry/Soldermask Top")
		(3 "B.Mask" user "Board Geometry/Soldermask Bottom")
		(17 "Dwgs.User" user "User.Drawings")
		(19 "Cmts.User" user "User.Comments")
		(21 "Eco1.User" user "User.Eco1")
		(23 "Eco2.User" user "User.Eco2")
		(25 "Edge.Cuts" user "Board Geometry/Outline")
		(27 "Margin" user)
		(31 "F.CrtYd" user "Package Geometry/Place Bound Top")
		(29 "B.CrtYd" user "Package Geometry/Place Bound Bottom")
		(35 "F.Fab" user "Ref Des/Assembly Top")
		(33 "B.Fab" user "Ref Des/Assembly Bottom")
	)
	(footprint ""
		(layer "F.Cu")
		(at 496.000024 -5.500116 90)
		(property "Reference" "JA9G1"
			(at 0 0 90)
			(layer "F.SilkS")
			(hide yes)
			(effects
				(font
					(size 1.27 1.27)
				)
			)
		)
		(property "Value" "*"
			(at 12.1031 -6.0325 90)
			(unlocked yes)
			(layer "F.Fab")
			(hide yes)
			(effects
				(font
					(size 1.27 1.016)
					(thickness 0.1524)
				)
			)
		)
		(property "Device Type" "SKT-RJ45-LED-XFOR-1-GP_SOCKET-A"
			(at 12.1031 -7.5565 90)
			(unlocked yes)
			(layer "F.Fab")
			(hide yes)
			(effects
				(font
					(size 1.27 1.016)
					(thickness 0.1524)
				)
			)
		)
		(duplicate_pad_numbers_are_jumpers no)
		(pad "1" thru_hole rect
			(at 9.299956 0 90)
			(size 1.4986 4.3942)
			(drill oval 0.508 1.8034
				(offset -0.0508 0)
			)
			(layers "*.Cu" "*.Mask")
			(remove_unused_layers no)
			(net "GND")
			(clearance 0.0127)
			(thermal_gap 0.0127)
			(padstack
				(mode front_inner_back)
				(layer "Inner"
					(shape oval)
					(size 1.2192 2.5146)
					(clearance 0.1524)
				)
				(layer "B.Cu"
					(shape oval)
					(size 1.2192 2.5146)
					(clearance 0.1524)
				)
			)
		)
		(pad "2" thru_hole rect
			(at -9.299956 0 90)
			(size 1.4986 4.3942)
			(drill oval 0.508 1.8034
				(offset 0.0508 0)
			)
			(layers "*.Cu" "*.Mask")
			(remove_unused_layers no)
			(net "GND")
			(clearance 0.0127)
			(thermal_gap 0.0127)
			(padstack
				(mode front_inner_back)
				(layer "Inner"
					(shape oval)
					(size 1.2192 2.5146)
					(clearance 0.1524)
				)
				(layer "B.Cu"
					(shape oval)
					(size 1.2192 2.5146)
					(clearance 0.1524)
				)
			)
		)
		(pad "L1" thru_hole circle
			(at 7.104888 -13.159994 90)
			(size 1.3208 1.3208)
			(drill 0.9144)
			(layers "*.Cu" "*.Mask")
			(remove_unused_layers no)
			(net "LED_LAN_2_R_N")
			(clearance 0.1524)
			(thermal_gap 0.1524)
		)
		(pad "L2" thru_hole circle
			(at 6.089904 -14.429994 90)
			(size 1.3208 1.3208)
			(drill 0.9144)
			(layers "*.Cu" "*.Mask")
			(remove_unused_layers no)
			(net "LED_LAN_0_R_N")
			(clearance 0.1524)
			(thermal_gap 0.1524)
		)
		(pad "L3" thru_hole circle
			(at -6.089904 -14.429994 90)
			(size 1.3208 1.3208)
			(drill 0.9144)
			(layers "*.Cu" "*.Mask")
			(remove_unused_layers no)
			(net "LED_LAN_1_R_N")
			(clearance 0.1524)
			(thermal_gap 0.1524)
		)
		(pad "L4" thru_hole circle
			(at -7.104888 -13.159994 90)
			(size 1.3208 1.3208)
			(drill 0.9144)
			(layers "*.Cu" "*.Mask")
			(remove_unused_layers no)
			(net "NIC_LED_ACT_ANODE_R")
			(clearance 0.1524)
			(thermal_gap 0.1524)
		)
		(pad "R1" thru_hole circle
			(at 5.07492 -13.159994 90)
			(size 1.3208 1.3208)
			(drill 0.9144)
			(layers "*.Cu" "*.Mask")
			(remove_unused_layers no)
			(net "GND_LAN_TRCT1234_C")
			(clearance 0.1524)
			(thermal_gap 0.1524)
		)
		(pad "R2" thru_hole circle
			(at 4.059936 -14.429994 90)
			(size 1.3208 1.3208)
			(drill 0.9144)
			(layers "*.Cu" "*.Mask")
			(remove_unused_layers no)
			(net "NIC_MDI_SPRV_RJ45_0_R_DP")
			(clearance 0.1524)
			(thermal_gap 0.1524)
		)
		(pad "R3" thru_hole circle
			(at 3.044952 -13.159994 90)
			(size 1.3208 1.3208)
			(drill 0.9144)
			(layers "*.Cu" "*.Mask")
			(remove_unused_layers no)
			(net "NIC_MDI_SPRV_RJ45_0_R_DN")
			(clearance 0.1524)
			(thermal_gap 0.1524)
		)
		(pad "R4" thru_hole circle
			(at 2.029968 -14.429994 90)
			(size 1.3208 1.3208)
			(drill 0.9144)
			(layers "*.Cu" "*.Mask")
			(remove_unused_layers no)
			(net "NIC_MDI_SPRV_RJ45_1_R_DP")
			(clearance 0.1524)
			(thermal_gap 0.1524)
		)
		(pad "R5" thru_hole circle
			(at 1.014984 -13.159994 90)
			(size 1.3208 1.3208)
			(drill 0.9144)
			(layers "*.Cu" "*.Mask")
			(remove_unused_layers no)
			(net "NIC_MDI_SPRV_RJ45_1_R_DN")
			(clearance 0.1524)
			(thermal_gap 0.1524)
		)
		(pad "R6" thru_hole circle
			(at 0 -14.429994 90)
			(size 1.3208 1.3208)
			(drill 0.9144)
			(layers "*.Cu" "*.Mask")
			(remove_unused_layers no)
			(net "GND")
			(clearance 0.1524)
			(thermal_gap 0.1524)
		)
		(pad "R7" thru_hole circle
			(at -1.014984 -13.159994 90)
			(size 1.3208 1.3208)
			(drill 0.9144)
			(layers "*.Cu" "*.Mask")
			(remove_unused_layers no)
			(net "NIC_MDI_SPRV_RJ45_2_R_DP")
			(clearance 0.1524)
			(thermal_gap 0.1524)
		)
		(pad "R8" thru_hole circle
			(at -2.029968 -14.429994 90)
			(size 1.3208 1.3208)
			(drill 0.9144)
			(layers "*.Cu" "*.Mask")
			(remove_unused_layers no)
			(net "NIC_MDI_SPRV_RJ45_2_R_DN")
			(clearance 0.1524)
			(thermal_gap 0.1524)
		)
		(pad "R9" thru_hole circle
			(at -3.044952 -13.159994 90)
			(size 1.3208 1.3208)
			(drill 0.9144)
			(layers "*.Cu" "*.Mask")
			(remove_unused_layers no)
			(net "NIC_MDI_SPRV_RJ45_3_R_DP")
			(clearance 0.1524)
			(thermal_gap 0.1524)
		)
		(pad "R10" thru_hole circle
			(at -4.059936 -14.429994 90)
			(size 1.3208 1.3208)
			(drill 0.9144)
			(layers "*.Cu" "*.Mask")
			(remove_unused_layers no)
			(net "NIC_MDI_SPRV_RJ45_3_R_DN")
			(clearance 0.1524)
			(thermal_gap 0.1524)
		)
		(pad "R11" thru_hole circle
			(at -5.07492 -13.159994 90)
			(size 1.3208 1.3208)
			(drill 0.9144)
			(layers "*.Cu" "*.Mask")
			(remove_unused_layers no)
			(net "GND_LAN_TRCT1234_C")
			(clearance 0.1524)
			(thermal_gap 0.1524)
		)
	)
)
